(kicad_pcb
	(version 20260206)
	(generator "pcbnew")
	(generator_version "10.0")
	(general
		(thickness 1.6)
		(legacy_teardrops no)
	)
	(paper "A4")
	(title_block
		(title "Wiwynn_Tioga_Pass_MB.brd")
		(comment 1 "Tioga Pass / footprints 2336-2343 of 4770")
	)
	(layers
		(0 "F.Cu" signal "TOP")
		(4 "In1.Cu" signal "L2GND")
		(6 "In2.Cu" signal "L3")
		(8 "In3.Cu" signal "L4GND")
		(10 "In4.Cu" signal "L5")
		(12 "In5.Cu" signal "L6GND")
		(14 "In6.Cu" signal "L7VCC")
		(16 "In7.Cu" signal "L8VCC")
		(18 "In8.Cu" signal "L9GND")
		(20 "In9.Cu" signal "L10")
		(22 "In10.Cu" signal "L11GND")
		(24 "In11.Cu" signal "L12")
		(26 "In12.Cu" signal "L13GND")
		(2 "B.Cu" signal "BOTTOM")
		(9 "F.Adhes" user "F.Adhesive")
		(11 "B.Adhes" user "B.Adhesive")
		(13 "F.Paste" user "Package Geometry/Pastemask Top")
		(15 "B.Paste" user "Package Geometry/Pastemask Bottom")
		(5 "F.SilkS" user "Ref Des/Silkscreen Top")
		(7 "B.SilkS" user "Ref Des/Silkscreen Bottom")
		(1 "F.Mask" user "Board Geometry/Soldermask Top")
		(3 "B.Mask" user "Board Geometry/Soldermask Bottom")
		(17 "Dwgs.User" user "User.Drawings")
		(19 "Cmts.User" user "User.Comments")
		(21 "Eco1.User" user "User.Eco1")
		(23 "Eco2.User" user "User.Eco2")
		(25 "Edge.Cuts" user "Board Geometry/Outline")
		(27 "Margin" user)
		(31 "F.CrtYd" user "Package Geometry/Place Bound Top")
		(29 "B.CrtYd" user "Package Geometry/Place Bound Bottom")
		(35 "F.Fab" user "Ref Des/Assembly Top")
		(33 "B.Fab" user "Ref Des/Assembly Bottom")
	)
	(footprint ""
		(layer "B.Cu")
		(at 388.154672 -154.721306)
		(property "Reference" "C3L10"
			(at 0 0 0)
			(layer "B.SilkS")
			(hide yes)
			(effects
				(font
					(size 1.27 1.27)
				)
				(justify mirror)
			)
		)
		(property "Value" ""
			(at 0 0 0)
			(layer "B.Fab")
			(effects
				(font
					(size 1.27 1.27)
				)
				(justify mirror)
			)
		)
		(duplicate_pad_numbers_are_jumpers no)
		(fp_poly
			(pts
				(xy 0.7239 -0.2159) (xy -0.7239 -0.2159) (xy -0.7239 1.9939) (xy 0.7239 1.9939)
			)
			(stroke
				(width 0)
				(type default)
			)
			(fill no)
			(layer "B.CrtYd")
		)
		(fp_line
			(start -0.7239 -0.2159)
			(end 0.7239 -0.2159)
			(stroke
				(width 0.1)
				(type default)
			)
			(layer "B.Fab")
		)
		(fp_line
			(start -0.7239 1.9939)
			(end -0.7239 -0.2159)
			(stroke
				(width 0.1)
				(type default)
			)
			(layer "B.Fab")
		)
		(fp_line
			(start 0.7239 -0.2159)
			(end 0.7239 1.9939)
			(stroke
				(width 0.1)
				(type default)
			)
			(layer "B.Fab")
		)
		(fp_line
			(start 0.7239 1.9939)
			(end -0.7239 1.9939)
			(stroke
				(width 0.1)
				(type default)
			)
			(layer "B.Fab")
		)
		(pad "1" smd rect
			(at 0 0 180)
			(size 1.27 1.016)
			(layers "B.Cu" "B.Mask" "B.Paste")
			(net "VR_FET_SW_P12V_STBY_PVDDQ_DEF")
		)
		(pad "2" smd rect
			(at 0 1.778 180)
			(size 1.27 1.016)
			(layers "B.Cu" "B.Mask" "B.Paste")
			(net "GND")
		)
		(zone
			(layer "B.Cu")
			(hatch none 0.5)
			(connect_pads
				(clearance 0)
			)
			(min_thickness 0.25)
			(keepout
				(tracks not_allowed)
				(vias allowed)
				(pads allowed)
				(copperpour not_allowed)
				(footprints allowed)
			)
			(placement
				(enabled no)
				(sheetname "")
			)
			(fill
				(thermal_gap 0.5)
				(thermal_bridge_width 0.5)
				(island_removal_mode 0)
			)
			(polygon
				(pts
					(xy 388.789672 -154.213306) (xy 387.519672 -154.213306) (xy 387.519672 -153.451306) (xy 388.789672 -153.451306)
				)
			)
		)
	)
	(footprint ""
		(layer "B.Cu")
		(at 262.206486 -73.51014)
		(property "Reference" "C5P35"
			(at 0 0 0)
			(layer "B.SilkS")
			(hide yes)
			(effects
				(font
					(size 1.27 1.27)
				)
				(justify mirror)
			)
		)
		(property "Value" ""
			(at 0 0 0)
			(layer "B.Fab")
			(effects
				(font
					(size 1.27 1.27)
				)
				(justify mirror)
			)
		)
		(duplicate_pad_numbers_are_jumpers no)
		(fp_poly
			(pts
				(xy 0.7239 -0.2159) (xy -0.7239 -0.2159) (xy -0.7239 1.9939) (xy 0.7239 1.9939)
			)
			(stroke
				(width 0)
				(type default)
			)
			(fill no)
			(layer "B.CrtYd")
		)
		(fp_line
			(start -0.7239 -0.2159)
			(end 0.7239 -0.2159)
			(stroke
				(width 0.1)
				(type default)
			)
			(layer "B.Fab")
		)
		(fp_line
			(start -0.7239 1.9939)
			(end -0.7239 -0.2159)
			(stroke
				(width 0.1)
				(type default)
			)
			(layer "B.Fab")
		)
		(fp_line
			(start 0.7239 -0.2159)
			(end 0.7239 1.9939)
			(stroke
				(width 0.1)
				(type default)
			)
			(layer "B.Fab")
		)
		(fp_line
			(start 0.7239 1.9939)
			(end -0.7239 1.9939)
			(stroke
				(width 0.1)
				(type default)
			)
			(layer "B.Fab")
		)
		(pad "1" smd rect
			(at 0 0 180)
			(size 1.27 1.016)
			(layers "B.Cu" "B.Mask" "B.Paste")
			(net "PVCCIN_CPU0")
		)
		(pad "2" smd rect
			(at 0 1.778 180)
			(size 1.27 1.016)
			(layers "B.Cu" "B.Mask" "B.Paste")
			(net "GND")
		)
		(zone
			(layer "B.Cu")
			(hatch none 0.5)
			(connect_pads
				(clearance 0)
			)
			(min_thickness 0.25)
			(keepout
				(tracks not_allowed)
				(vias allowed)
				(pads allowed)
				(copperpour not_allowed)
				(footprints allowed)
			)
			(placement
				(enabled no)
				(sheetname "")
			)
			(fill
				(thermal_gap 0.5)
				(thermal_bridge_width 0.5)
				(island_removal_mode 0)
			)
			(polygon
				(pts
					(xy 262.841486 -73.00214) (xy 261.571486 -73.00214) (xy 261.571486 -72.24014) (xy 262.841486 -72.24014)
				)
			)
		)
	)
	(footprint ""
		(layer "B.Cu")
		(at 409.6004 -147.955 -90)
		(property "Reference" "C2L21"
			(at 0 0 90)
			(layer "B.SilkS")
			(hide yes)
			(effects
				(font
					(size 1.27 1.27)
				)
				(justify mirror)
			)
		)
		(property "Value" ""
			(at 0 0 90)
			(layer "B.Fab")
			(effects
				(font
					(size 1.27 1.27)
				)
				(justify mirror)
			)
		)
		(duplicate_pad_numbers_are_jumpers no)
		(fp_poly
			(pts
				(xy -0.3048 -0.1016) (xy -0.3048 0.9906) (xy 0.3048 0.9906) (xy 0.3048 -0.1016)
			)
			(stroke
				(width 0)
				(type default)
			)
			(fill no)
			(layer "B.CrtYd")
		)
		(fp_line
			(start -0.3048 0.9906)
			(end -0.3048 -0.1016)
			(stroke
				(width 0.1)
				(type default)
			)
			(layer "B.Fab")
		)
		(fp_line
			(start 0.3048 0.9906)
			(end -0.3048 0.9906)
			(stroke
				(width 0.1)
				(type default)
			)
			(layer "B.Fab")
		)
		(fp_line
			(start -0.3048 -0.1016)
			(end 0.3048 -0.1016)
			(stroke
				(width 0.1)
				(type default)
			)
			(layer "B.Fab")
		)
		(fp_line
			(start 0.3048 -0.1016)
			(end 0.3048 0.9906)
			(stroke
				(width 0.1)
				(type default)
			)
			(layer "B.Fab")
		)
		(pad "1" smd rect
			(at 0 0 90)
			(size 0.508 0.508)
			(layers "B.Cu" "B.Mask" "B.Paste")
			(net "SATA6G_P7_TX_C_DN")
		)
		(pad "2" smd rect
			(at 0 0.889 90)
			(size 0.508 0.508)
			(layers "B.Cu" "B.Mask" "B.Paste")
			(net "SATA6G_PCH_PCIE_UP_SATA_TXN<7>")
		)
		(zone
			(layer "B.Cu")
			(hatch none 0.5)
			(connect_pads
				(clearance 0)
			)
			(min_thickness 0.25)
			(keepout
				(tracks not_allowed)
				(vias allowed)
				(pads allowed)
				(copperpour not_allowed)
				(footprints allowed)
			)
			(placement
				(enabled no)
				(sheetname "")
			)
			(fill
				(thermal_gap 0.5)
				(thermal_bridge_width 0.5)
				(island_removal_mode 0)
			)
			(polygon
				(pts
					(xy 408.9654 -147.701) (xy 408.9654 -148.209) (xy 409.3464 -148.209) (xy 409.3464 -147.701)
				)
			)
		)
		(zone
			(layer "B.Cu")
			(hatch none 0.5)
			(connect_pads
				(clearance 0)
			)
			(min_thickness 0.25)
			(keepout
				(tracks allowed)
				(vias not_allowed)
				(pads allowed)
				(copperpour not_allowed)
				(footprints allowed)
			)
			(placement
				(enabled no)
				(sheetname "")
			)
			(fill
				(thermal_gap 0.5)
				(thermal_bridge_width 0.5)
				(island_removal_mode 0)
			)
			(polygon
				(pts
					(xy 409.3464 -147.701) (xy 409.3464 -148.209) (xy 408.9654 -148.209) (xy 408.9654 -147.701)
				)
			)
		)
	)
	(footprint ""
		(layer "B.Cu")
		(at 221.488 -28.194)
		(property "Reference" ""
			(at 0 0 0)
			(layer "B.SilkS")
			(hide yes)
			(effects
				(font
					(size 1.27 1.27)
				)
				(justify mirror)
			)
		)
		(property "Value" ""
			(at 0 0 0)
			(layer "B.Fab")
			(effects
				(font
					(size 1.27 1.27)
				)
				(justify mirror)
			)
		)
		(duplicate_pad_numbers_are_jumpers no)
		(fp_poly
			(pts
				(arc
					(start 2.032 0)
					(mid -2.032 0)
					(end 2.032 0)
				)
			)
			(stroke
				(width 0)
				(type default)
			)
			(fill no)
			(layer "B.CrtYd")
		)
		(pad "1" smd circle
			(at 0 0 180)
			(size 1.016 1.016)
			(layers "B.Cu" "B.Mask" "B.Paste")
			(net "Net_396")
		)
		(zone
			(layers "F.Cu" "B.Cu" "In1.Cu" "In2.Cu" "In3.Cu" "In4.Cu" "In5.Cu" "In6.Cu"
				"In7.Cu" "In8.Cu" "In9.Cu" "In10.Cu" "In11.Cu" "In12.Cu"
			)
			(hatch none 0.5)
			(connect_pads
				(clearance 0)
			)
			(min_thickness 0.25)
			(keepout
				(tracks allowed)
				(vias not_allowed)
				(pads allowed)
				(copperpour not_allowed)
				(footprints allowed)
			)
			(placement
				(enabled no)
				(sheetname "")
			)
			(fill
				(thermal_gap 0.5)
				(thermal_bridge_width 0.5)
				(island_removal_mode 0)
			)
			(polygon
				(pts
					(arc
						(start 223.012 -28.194)
						(mid 219.964 -28.194)
						(end 223.012 -28.194)
					)
				)
			)
		)
		(zone
			(layer "B.Cu")
			(hatch none 0.5)
			(connect_pads
				(clearance 0)
			)
			(min_thickness 0.25)
			(keepout
				(tracks not_allowed)
				(vias allowed)
				(pads allowed)
				(copperpour not_allowed)
				(footprints allowed)
			)
			(placement
				(enabled no)
				(sheetname "")
			)
			(fill
				(thermal_gap 0.5)
				(thermal_bridge_width 0.5)
				(island_removal_mode 0)
			)
			(polygon
				(pts
					(arc
						(start 223.012 -28.194)
						(mid 219.964 -28.194)
						(end 223.012 -28.194)
					)
				)
			)
		)
	)
	(footprint ""
		(layer "B.Cu")
		(at 116.332 -74.93 90)
		(property "Reference" "R7P15"
			(at 0 0 90)
			(layer "B.SilkS")
			(hide yes)
			(effects
				(font
					(size 1.27 1.27)
				)
				(justify mirror)
			)
		)
		(property "Value" ""
			(at 0 0 90)
			(layer "B.Fab")
			(effects
				(font
					(size 1.27 1.27)
				)
				(justify mirror)
			)
		)
		(duplicate_pad_numbers_are_jumpers no)
		(fp_poly
			(pts
				(xy 0.2794 -0.1016) (xy -0.2794 -0.1016) (xy -0.2794 0.9906) (xy 0.2794 0.9906)
			)
			(stroke
				(width 0)
				(type default)
			)
			(fill no)
			(layer "B.CrtYd")
		)
		(fp_line
			(start 0.2794 -0.1016)
			(end 0.2794 0.9906)
			(stroke
				(width 0.1)
				(type default)
			)
			(layer "B.Fab")
		)
		(fp_line
			(start -0.2794 -0.1016)
			(end 0.2794 -0.1016)
			(stroke
				(width 0.1)
				(type default)
			)
			(layer "B.Fab")
		)
		(fp_line
			(start 0.2794 0.9906)
			(end -0.2794 0.9906)
			(stroke
				(width 0.1)
				(type default)
			)
			(layer "B.Fab")
		)
		(fp_line
			(start -0.2794 0.9906)
			(end -0.2794 -0.1016)
			(stroke
				(width 0.1)
				(type default)
			)
			(layer "B.Fab")
		)
		(pad "1" smd rect
			(at 0 0 270)
			(size 0.508 0.508)
			(layers "B.Cu" "B.Mask" "B.Paste")
			(net "GND")
		)
		(pad "2" smd rect
			(at 0 0.889 270)
			(size 0.508 0.508)
			(layers "B.Cu" "B.Mask" "B.Paste")
			(net "PD_CPU1_KSFC_DIS")
		)
		(zone
			(layer "B.Cu")
			(hatch none 0.5)
			(connect_pads
				(clearance 0)
			)
			(min_thickness 0.25)
			(keepout
				(tracks allowed)
				(vias not_allowed)
				(pads allowed)
				(copperpour not_allowed)
				(footprints allowed)
			)
			(placement
				(enabled no)
				(sheetname "")
			)
			(fill
				(thermal_gap 0.5)
				(thermal_bridge_width 0.5)
				(island_removal_mode 0)
			)
			(polygon
				(pts
					(xy 116.586 -75.184) (xy 116.586 -74.676) (xy 116.967 -74.676) (xy 116.967 -75.184)
				)
			)
		)
		(zone
			(layer "B.Cu")
			(hatch none 0.5)
			(connect_pads
				(clearance 0)
			)
			(min_thickness 0.25)
			(keepout
				(tracks not_allowed)
				(vias allowed)
				(pads allowed)
				(copperpour not_allowed)
				(footprints allowed)
			)
			(placement
				(enabled no)
				(sheetname "")
			)
			(fill
				(thermal_gap 0.5)
				(thermal_bridge_width 0.5)
				(island_removal_mode 0)
			)
			(polygon
				(pts
					(xy 116.967 -75.184) (xy 116.967 -74.676) (xy 116.586 -74.676) (xy 116.586 -75.184)
				)
			)
		)
	)
	(footprint ""
		(layer "B.Cu")
		(at 492.4044 -116.082318)
		(property "Reference" "R9B7"
			(at 0 0 0)
			(layer "B.SilkS")
			(hide yes)
			(effects
				(font
					(size 1.27 1.27)
				)
				(justify mirror)
			)
		)
		(property "Value" "*"
			(at -0.064008 -4.108196 0)
			(unlocked yes)
			(layer "B.Fab")
			(hide yes)
			(effects
				(font
					(size 1.27 1.016)
					(thickness 0.1524)
				)
				(justify mirror)
			)
		)
		(property "Device Type" "887R2F-L-GP_SMD-RG-887R2F-L-GPA"
			(at -0.064008 -5.632196 0)
			(unlocked yes)
			(layer "B.Fab")
			(hide yes)
			(effects
				(font
					(size 1.27 1.016)
					(thickness 0.1524)
				)
				(justify mirror)
			)
		)
		(duplicate_pad_numbers_are_jumpers no)
		(fp_line
			(start -0.508 -0.9398)
			(end 0.508 -0.9398)
			(stroke
				(width 0.1524)
				(type default)
			)
			(layer "B.SilkS")
		)
		(fp_line
			(start 0.508 -0.9398)
			(end 0.508 0.9398)
			(stroke
				(width 0.1524)
				(type default)
			)
			(layer "B.SilkS")
		)
		(fp_rect
			(start 0.508 0.9398)
			(end -0.508 -0.9398)
			(stroke
				(width 0)
				(type default)
			)
			(fill no)
			(layer "B.CrtYd")
		)
		(fp_rect
			(start 0.508 0.9398)
			(end -0.508 -0.9398)
			(stroke
				(width 0)
				(type default)
			)
			(fill no)
			(layer "B.Fab")
		)
		(pad "1" smd custom
			(at 0 -0.4445 180)
			(size 0.1397 0.1397)
			(layers "B.Cu" "B.Mask" "B.Paste")
			(net "FM_MEZZA_PRSNT1_N")
			(options
				(clearance outline)
				(anchor circle)
			)
			(primitives
				(gr_poly
					(pts
						(arc
							(start -0.1778 0.2794)
							(mid -0.249642 0.249642)
							(end -0.2794 0.1778)
						)
						(arc
							(start -0.2794 -0.1778)
							(mid -0.249642 -0.249642)
							(end -0.1778 -0.2794)
						)
						(arc
							(start 0.1778 -0.2794)
							(mid 0.249642 -0.249642)
							(end 0.2794 -0.1778)
						)
						(arc
							(start 0.2794 0.1778)
							(mid 0.249642 0.249642)
							(end 0.1778 0.2794)
						)
					)
					(width 0)
					(fill yes)
				)
			)
		)
		(pad "2" smd custom
			(at 0 0.4445 180)
			(size 0.1397 0.1397)
			(layers "B.Cu" "B.Mask" "B.Paste")
			(net "GND")
			(options
				(clearance outline)
				(anchor circle)
			)
			(primitives
				(gr_poly
					(pts
						(arc
							(start -0.1778 0.2794)
							(mid -0.249642 0.249642)
							(end -0.2794 0.1778)
						)
						(arc
							(start -0.2794 -0.1778)
							(mid -0.249642 -0.249642)
							(end -0.1778 -0.2794)
						)
						(arc
							(start 0.1778 -0.2794)
							(mid 0.249642 -0.249642)
							(end 0.2794 -0.1778)
						)
						(arc
							(start 0.2794 0.1778)
							(mid 0.249642 0.249642)
							(end 0.1778 0.2794)
						)
					)
					(width 0)
					(fill yes)
				)
			)
		)
	)
	(footprint ""
		(layer "B.Cu")
		(at 487.045 -140.8176 90)
		(property "Reference" "R1L36"
			(at 0 0 90)
			(layer "B.SilkS")
			(hide yes)
			(effects
				(font
					(size 1.27 1.27)
				)
				(justify mirror)
			)
		)
		(property "Value" ""
			(at 0 0 90)
			(layer "B.Fab")
			(effects
				(font
					(size 1.27 1.27)
				)
				(justify mirror)
			)
		)
		(duplicate_pad_numbers_are_jumpers no)
		(fp_poly
			(pts
				(xy 0.2794 -0.1016) (xy -0.2794 -0.1016) (xy -0.2794 0.9906) (xy 0.2794 0.9906)
			)
			(stroke
				(width 0)
				(type default)
			)
			(fill no)
			(layer "B.CrtYd")
		)
		(fp_line
			(start 0.2794 -0.1016)
			(end 0.2794 0.9906)
			(stroke
				(width 0.1)
				(type default)
			)
			(layer "B.Fab")
		)
		(fp_line
			(start -0.2794 -0.1016)
			(end 0.2794 -0.1016)
			(stroke
				(width 0.1)
				(type default)
			)
			(layer "B.Fab")
		)
		(fp_line
			(start 0.2794 0.9906)
			(end -0.2794 0.9906)
			(stroke
				(width 0.1)
				(type default)
			)
			(layer "B.Fab")
		)
		(fp_line
			(start -0.2794 0.9906)
			(end -0.2794 -0.1016)
			(stroke
				(width 0.1)
				(type default)
			)
			(layer "B.Fab")
		)
		(pad "1" smd rect
			(at 0 0 270)
			(size 0.508 0.508)
			(layers "B.Cu" "B.Mask" "B.Paste")
			(net "P3V3_STBY")
		)
		(pad "2" smd rect
			(at 0 0.889 270)
			(size 0.508 0.508)
			(layers "B.Cu" "B.Mask" "B.Paste")
			(net "FM_DB_PRESENT")
		)
		(zone
			(layer "B.Cu")
			(hatch none 0.5)
			(connect_pads
				(clearance 0)
			)
			(min_thickness 0.25)
			(keepout
				(tracks allowed)
				(vias not_allowed)
				(pads allowed)
				(copperpour not_allowed)
				(footprints allowed)
			)
			(placement
				(enabled no)
				(sheetname "")
			)
			(fill
				(thermal_gap 0.5)
				(thermal_bridge_width 0.5)
				(island_removal_mode 0)
			)
			(polygon
				(pts
					(xy 487.299 -141.0716) (xy 487.299 -140.5636) (xy 487.68 -140.5636) (xy 487.68 -141.0716)
				)
			)
		)
		(zone
			(layer "B.Cu")
			(hatch none 0.5)
			(connect_pads
				(clearance 0)
			)
			(min_thickness 0.25)
			(keepout
				(tracks not_allowed)
				(vias allowed)
				(pads allowed)
				(copperpour not_allowed)
				(footprints allowed)
			)
			(placement
				(enabled no)
				(sheetname "")
			)
			(fill
				(thermal_gap 0.5)
				(thermal_bridge_width 0.5)
				(island_removal_mode 0)
			)
			(polygon
				(pts
					(xy 487.68 -141.0716) (xy 487.68 -140.5636) (xy 487.299 -140.5636) (xy 487.299 -141.0716)
				)
			)
		)
	)
	(footprint ""
		(layer "B.Cu")
		(at 389.33755 -106.25455 180)
		(property "Reference" "C2N16"
			(at 0 0 0)
			(layer "B.SilkS")
			(hide yes)
			(effects
				(font
					(size 1.27 1.27)
				)
				(justify mirror)
			)
		)
		(property "Value" ""
			(at 0 0 0)
			(layer "B.Fab")
			(effects
				(font
					(size 1.27 1.27)
				)
				(justify mirror)
			)
		)
		(duplicate_pad_numbers_are_jumpers no)
		(fp_rect
			(start 0.2794 0.9144)
			(end -0.2794 -0.1143)
			(stroke
				(width 0)
				(type default)
			)
			(fill no)
			(layer "B.CrtYd")
		)
		(fp_line
			(start 0.2794 0.9144)
			(end 0.2794 -0.1143)
			(stroke
				(width 0.1)
				(type default)
			)
			(layer "B.Fab")
		)
		(fp_line
			(start 0.2794 -0.1143)
			(end -0.2794 -0.1143)
			(stroke
				(width 0.1)
				(type default)
			)
			(layer "B.Fab")
		)
		(fp_line
			(start -0.2794 0.9144)
			(end 0.2794 0.9144)
			(stroke
				(width 0.1)
				(type default)
			)
			(layer "B.Fab")
		)
		(fp_line
			(start -0.2794 -0.1143)
			(end -0.2794 0.9144)
			(stroke
				(width 0.1)
				(type default)
			)
			(layer "B.Fab")
		)
		(pad "1" smd custom
			(at 0 0 90)
			(size 0.10414 0.10414)
			(layers "B.Cu" "B.Mask" "B.Paste")
			(net "P1V8_PCH_STBY")
			(options
				(clearance outline)
				(anchor circle)
			)
			(primitives
				(gr_poly
					(pts
						(xy -0.20828 -0.08636) (xy -0.20828 0.08636) (xy -0.08636 0.20828) (xy 0.086614 0.20828) (xy 0.20828 0.086614)
						(xy 0.20828 -0.08636) (xy 0.08636 -0.20828) (xy -0.08636 -0.20828)
					)
					(width 0)
					(fill yes)
				)
			)
		)
		(pad "2" smd custom
			(at 0 0.8001 90)
			(size 0.10414 0.10414)
			(layers "B.Cu" "B.Mask" "B.Paste")
			(net "GND")
			(options
				(clearance outline)
				(anchor circle)
			)
			(primitives
				(gr_poly
					(pts
						(xy -0.20828 -0.08636) (xy -0.20828 0.08636) (xy -0.08636 0.20828) (xy 0.086614 0.20828) (xy 0.20828 0.086614)
						(xy 0.20828 -0.08636) (xy 0.08636 -0.20828) (xy -0.08636 -0.20828)
					)
					(width 0)
					(fill yes)
				)
			)
		)
		(zone
			(layer "B.Cu")
			(hatch none 0.5)
			(connect_pads
				(clearance 0)
			)
			(min_thickness 0.25)
			(keepout
				(tracks allowed)
				(vias not_allowed)
				(pads allowed)
				(copperpour not_allowed)
				(footprints allowed)
			)
			(placement
				(enabled no)
				(sheetname "")
			)
			(fill
				(thermal_gap 0.5)
				(thermal_bridge_width 0.5)
				(island_removal_mode 0)
			)
			(polygon
				(pts
					(xy 389.24992 -106.4641) (xy 389.24992 -106.8451) (xy 389.42518 -106.8451) (xy 389.425434 -106.4641)
				)
			)
		)
		(zone
			(layer "B.Cu")
			(hatch none 0.5)
			(connect_pads
				(clearance 0)
			)
			(min_thickness 0.25)
			(keepout
				(tracks not_allowed)
				(vias allowed)
				(pads allowed)
				(copperpour not_allowed)
				(footprints allowed)
			)
			(placement
				(enabled no)
				(sheetname "")
			)
			(fill
				(thermal_gap 0.5)
				(thermal_bridge_width 0.5)
				(island_removal_mode 0)
			)
			(polygon
				(pts
					(xy 389.24992 -106.4641) (xy 389.24992 -106.8451) (xy 389.42518 -106.8451) (xy 389.425434 -106.4641)
				)
			)
		)
	)
)
